(kicad_pcb
	(version 20260206)
	(generator "pcbnew")
	(generator_version "10.0")
	(general
		(thickness 1.6)
		(legacy_teardrops no)
	)
	(paper "A4")
	(title_block
		(title "Wiwynn_Tioga_Pass_MB.brd")
		(comment 1 "Tioga Pass / footprint 2254 of 4770 (U5D1), pads 1863-1964 of 3647")
	)
	(layers
		(0 "F.Cu" signal "TOP")
		(4 "In1.Cu" signal "L2GND")
		(6 "In2.Cu" signal "L3")
		(8 "In3.Cu" signal "L4GND")
		(10 "In4.Cu" signal "L5")
		(12 "In5.Cu" signal "L6GND")
		(14 "In6.Cu" signal "L7VCC")
		(16 "In7.Cu" signal "L8VCC")
		(18 "In8.Cu" signal "L9GND")
		(20 "In9.Cu" signal "L10")
		(22 "In10.Cu" signal "L11GND")
		(24 "In11.Cu" signal "L12")
		(26 "In12.Cu" signal "L13GND")
		(2 "B.Cu" signal "BOTTOM")
		(9 "F.Adhes" user "F.Adhesive")
		(11 "B.Adhes" user "B.Adhesive")
		(13 "F.Paste" user "Package Geometry/Pastemask Top")
		(15 "B.Paste" user "Package Geometry/Pastemask Bottom")
		(5 "F.SilkS" user "Ref Des/Silkscreen Top")
		(7 "B.SilkS" user "Ref Des/Silkscreen Bottom")
		(1 "F.Mask" user "Board Geometry/Soldermask Top")
		(3 "B.Mask" user "Board Geometry/Soldermask Bottom")
		(17 "Dwgs.User" user "User.Drawings")
		(19 "Cmts.User" user "User.Comments")
		(21 "Eco1.User" user "User.Eco1")
		(23 "Eco2.User" user "User.Eco2")
		(25 "Edge.Cuts" user "Board Geometry/Outline")
		(27 "Margin" user)
		(31 "F.CrtYd" user "Package Geometry/Place Bound Top")
		(29 "B.CrtYd" user "Package Geometry/Place Bound Bottom")
		(35 "F.Fab" user "Ref Des/Assembly Top")
		(33 "B.Fab" user "Ref Des/Assembly Bottom")
	)
	(footprint ""
		(layer "F.Cu")
		(at 270.000222 -76.550012 180)
		(property "Reference" "U5D1"
			(at 19.124422 31.601918 0)
			(unlocked yes)
			(layer "F.SilkS")
			(effects
				(font
					(size 0.7874 0.5842)
					(thickness 0.1524)
				)
			)
		)
		(property "Value" ""
			(at 0 0 180)
			(layer "F.Fab")
			(effects
				(font
					(size 1.27 1.27)
				)
			)
		)
		(duplicate_pad_numbers_are_jumpers no)
		(pad "CY1" smd custom
			(at -37.250624 14.025372 90)
			(size 0.10795 0.10795)
			(layers "F.Cu" "F.Mask" "F.Paste")
			(net "GND")
			(options
				(clearance outline)
				(anchor circle)
			)
			(primitives
				(gr_poly
					(pts
						(arc
							(start 0.2159 -0.0381)
							(mid 0 -0.254)
							(end -0.2159 -0.0381)
						)
						(arc
							(start -0.2159 0.0381)
							(mid 0 0.254)
							(end 0.2159 0.0381)
						)
					)
					(width 0)
					(fill yes)
				)
			)
		)
		(pad "CY3" smd circle
			(at -35.533584 14.025372)
			(size 0.4318 0.4318)
			(layers "F.Cu" "F.Mask" "F.Paste")
			(net "P3E_CPU0_PE2_SS_TXN<0>")
		)
		(pad "CY5" smd circle
			(at -33.816544 14.025372)
			(size 0.4318 0.4318)
			(layers "F.Cu" "F.Mask" "F.Paste")
			(net "P3E_CPU0_PE3_OCP_TXN<15>")
		)
		(pad "CY7" smd circle
			(at -32.099504 14.025372)
			(size 0.4318 0.4318)
			(layers "F.Cu" "F.Mask" "F.Paste")
			(net "P3E_CPU0_PE1_SS_RXP<1>")
		)
		(pad "CY9" smd circle
			(at -30.382464 14.025372)
			(size 0.4318 0.4318)
			(layers "F.Cu" "F.Mask" "F.Paste")
			(net "GND")
		)
		(pad "CY11" smd circle
			(at -28.665424 14.025372)
			(size 0.4318 0.4318)
			(layers "F.Cu" "F.Mask" "F.Paste")
			(net "P3E_CPU0_PE3_OCP_RXN<14>")
		)
		(pad "CY13" smd circle
			(at -26.948384 14.025372)
			(size 0.4318 0.4318)
			(layers "F.Cu" "F.Mask" "F.Paste")
			(net "GND")
		)
		(pad "CY15" smd circle
			(at -25.231598 14.025372)
			(size 0.4318 0.4318)
			(layers "F.Cu" "F.Mask" "F.Paste")
			(net "GND")
		)
		(pad "CY17" smd circle
			(at -23.514558 14.025372)
			(size 0.4318 0.4318)
			(layers "F.Cu" "F.Mask" "F.Paste")
			(net "PVCCIO_CPU0")
		)
		(pad "CY19" smd circle
			(at -21.797518 14.025372)
			(size 0.4318 0.4318)
			(layers "F.Cu" "F.Mask" "F.Paste")
			(net "GND")
		)
		(pad "CY21" smd circle
			(at -20.080478 14.025372)
			(size 0.4318 0.4318)
			(layers "F.Cu" "F.Mask" "F.Paste")
			(net "GND")
		)
		(pad "CY23" smd circle
			(at -18.363438 14.025372)
			(size 0.4318 0.4318)
			(layers "F.Cu" "F.Mask" "F.Paste")
			(net "TP_CPU0_RSVD_59")
		)
		(pad "CY25" smd circle
			(at -16.646398 14.025372)
			(size 0.4318 0.4318)
			(layers "F.Cu" "F.Mask" "F.Paste")
			(net "PVCCMCP_CPU0")
		)
		(pad "CY27" smd circle
			(at -14.929612 14.025372)
			(size 0.4318 0.4318)
			(layers "F.Cu" "F.Mask" "F.Paste")
			(net "M_F_DQ<58>")
		)
		(pad "CY29" smd circle
			(at -13.212572 14.025372)
			(size 0.4318 0.4318)
			(layers "F.Cu" "F.Mask" "F.Paste")
			(net "M_F_DQS_DN<16>")
		)
		(pad "CY31" smd circle
			(at -11.495532 14.025372)
			(size 0.4318 0.4318)
			(layers "F.Cu" "F.Mask" "F.Paste")
			(net "M_F_DQ<60>")
		)
		(pad "CY33" smd circle
			(at -9.778492 14.025372)
			(size 0.4318 0.4318)
			(layers "F.Cu" "F.Mask" "F.Paste")
			(net "M_F_DQ<50>")
		)
		(pad "CY35" smd circle
			(at -8.061452 14.025372)
			(size 0.4318 0.4318)
			(layers "F.Cu" "F.Mask" "F.Paste")
			(net "M_F_DQS_DN<15>")
		)
		(pad "CY37" smd circle
			(at -6.344412 14.025372)
			(size 0.4318 0.4318)
			(layers "F.Cu" "F.Mask" "F.Paste")
			(net "M_F_DQ<52>")
		)
		(pad "CY39" smd circle
			(at -4.627626 14.025372)
			(size 0.4318 0.4318)
			(layers "F.Cu" "F.Mask" "F.Paste")
			(net "TP_CPU0_RSVD_57")
		)
		(pad "CY41" smd circle
			(at -2.910586 14.025372)
			(size 0.4318 0.4318)
			(layers "F.Cu" "F.Mask" "F.Paste")
			(net "GND")
		)
		(pad "CY45" smd circle
			(at 2.052066 12.225274)
			(size 0.508 0.508)
			(layers "F.Cu" "F.Mask" "F.Paste")
			(net "GND")
		)
		(pad "CY47" smd circle
			(at 3.769106 12.225274)
			(size 0.4318 0.4318)
			(layers "F.Cu" "F.Mask" "F.Paste")
			(net "PVCCIN_CPU0")
		)
		(pad "CY49" smd circle
			(at 5.485892 12.225274)
			(size 0.4318 0.4318)
			(layers "F.Cu" "F.Mask" "F.Paste")
			(net "PVCCIN_CPU0")
		)
		(pad "CY51" smd circle
			(at 7.202932 12.225274)
			(size 0.4318 0.4318)
			(layers "F.Cu" "F.Mask" "F.Paste")
			(net "GND")
		)
		(pad "CY53" smd circle
			(at 8.919972 12.225274)
			(size 0.4318 0.4318)
			(layers "F.Cu" "F.Mask" "F.Paste")
			(net "TP_CPU0_RSVD_56")
		)
		(pad "CY55" smd circle
			(at 10.637012 12.225274)
			(size 0.4318 0.4318)
			(layers "F.Cu" "F.Mask" "F.Paste")
			(net "P3V3_STBY")
		)
		(pad "CY57" smd circle
			(at 12.354052 12.225274)
			(size 0.4318 0.4318)
			(layers "F.Cu" "F.Mask" "F.Paste")
			(net "TP_CPU0_RSVD_55")
		)
		(pad "CY59" smd circle
			(at 14.071092 12.225274)
			(size 0.4318 0.4318)
			(layers "F.Cu" "F.Mask" "F.Paste")
			(net "GND")
		)
		(pad "CY61" smd circle
			(at 15.787878 12.225274)
			(size 0.4318 0.4318)
			(layers "F.Cu" "F.Mask" "F.Paste")
			(net "GND")
		)
		(pad "CY63" smd circle
			(at 17.504918 12.225274)
			(size 0.4318 0.4318)
			(layers "F.Cu" "F.Mask" "F.Paste")
			(net "TP_CPU0_RSVD_54")
		)
		(pad "CY65" smd circle
			(at 19.221958 12.225274)
			(size 0.4318 0.4318)
			(layers "F.Cu" "F.Mask" "F.Paste")
			(net "GND")
		)
		(pad "CY67" smd circle
			(at 20.938998 12.225274)
			(size 0.4318 0.4318)
			(layers "F.Cu" "F.Mask" "F.Paste")
			(net "M_D_DQS_DP<17>")
		)
		(pad "CY69" smd circle
			(at 22.656038 12.225274)
			(size 0.4318 0.4318)
			(layers "F.Cu" "F.Mask" "F.Paste")
			(net "GND")
		)
		(pad "CY71" smd circle
			(at 24.373078 12.225274)
			(size 0.4318 0.4318)
			(layers "F.Cu" "F.Mask" "F.Paste")
			(net "FM_CPU0_PROC_ID0")
		)
		(pad "CY73" smd circle
			(at 26.090118 12.225274)
			(size 0.4318 0.4318)
			(layers "F.Cu" "F.Mask" "F.Paste")
			(net "TP_CPU0_RSVD_53")
		)
		(pad "CY75" smd circle
			(at 27.806904 12.225274)
			(size 0.4318 0.4318)
			(layers "F.Cu" "F.Mask" "F.Paste")
			(net "GND")
		)
		(pad "CY77" smd circle
			(at 29.523944 12.225274)
			(size 0.4318 0.4318)
			(layers "F.Cu" "F.Mask" "F.Paste")
			(net "GND")
		)
		(pad "CY79" smd circle
			(at 31.240984 12.225274)
			(size 0.4318 0.4318)
			(layers "F.Cu" "F.Mask" "F.Paste")
			(net "M_E_DQ<12>")
		)
		(pad "CY81" smd circle
			(at 32.958024 12.225274)
			(size 0.4318 0.4318)
			(layers "F.Cu" "F.Mask" "F.Paste")
			(net "M_E_DQ<9>")
		)
		(pad "CY83" smd circle
			(at 34.675064 12.225274)
			(size 0.4318 0.4318)
			(layers "F.Cu" "F.Mask" "F.Paste")
			(net "GND")
		)
		(pad "CY85" smd circle
			(at 36.392104 12.225274)
			(size 0.4318 0.4318)
			(layers "F.Cu" "F.Mask" "F.Paste")
			(net "GND")
		)
		(pad "D3" smd custom
			(at -35.533584 -23.617174 45)
			(size 0.10795 0.10795)
			(layers "F.Cu" "F.Mask" "F.Paste")
			(net "GND")
			(options
				(clearance outline)
				(anchor circle)
			)
			(primitives
				(gr_poly
					(pts
						(arc
							(start 0.2159 -0.0381)
							(mid 0 -0.254)
							(end -0.2159 -0.0381)
						)
						(arc
							(start -0.2159 0.0381)
							(mid 0 0.254)
							(end 0.2159 0.0381)
						)
					)
					(width 0)
					(fill yes)
				)
			)
		)
		(pad "D5" smd custom
			(at -33.816544 -23.617174 90)
			(size 0.10795 0.10795)
			(layers "F.Cu" "F.Mask" "F.Paste")
			(net "TP_CPU0_RSVD_287")
			(options
				(clearance outline)
				(anchor circle)
			)
			(primitives
				(gr_poly
					(pts
						(arc
							(start 0.2159 -0.0381)
							(mid 0 -0.254)
							(end -0.2159 -0.0381)
						)
						(arc
							(start -0.2159 0.0381)
							(mid 0 0.254)
							(end 0.2159 0.0381)
						)
					)
					(width 0)
					(fill yes)
				)
			)
		)
		(pad "D7" smd circle
			(at -32.099504 -23.617174)
			(size 0.4318 0.4318)
			(layers "F.Cu" "F.Mask" "F.Paste")
			(net "PVCCIO_CPU0")
		)
		(pad "D9" smd circle
			(at -30.382464 -23.617174)
			(size 0.4318 0.4318)
			(layers "F.Cu" "F.Mask" "F.Paste")
			(net "UPI_CPU0_CPU1_P1P1_DN<12>")
		)
		(pad "D11" smd circle
			(at -28.665424 -23.617174)
			(size 0.4318 0.4318)
			(layers "F.Cu" "F.Mask" "F.Paste")
			(net "GND")
		)
		(pad "D13" smd circle
			(at -26.948384 -23.617174)
			(size 0.4318 0.4318)
			(layers "F.Cu" "F.Mask" "F.Paste")
			(net "GND")
		)
		(pad "D15" smd circle
			(at -25.231598 -23.617174)
			(size 0.4318 0.4318)
			(layers "F.Cu" "F.Mask" "F.Paste")
			(net "UPI_CPU0_CPU1_P1P1_DN<7>")
		)
		(pad "D17" smd circle
			(at -23.514558 -23.617174)
			(size 0.4318 0.4318)
			(layers "F.Cu" "F.Mask" "F.Paste")
			(net "TP_CPU0_RSVD_286")
		)
		(pad "D25" smd circle
			(at -16.646398 -23.617174)
			(size 0.4318 0.4318)
			(layers "F.Cu" "F.Mask" "F.Paste")
			(net "GND")
		)
		(pad "D27" smd circle
			(at -14.929612 -23.617174)
			(size 0.4318 0.4318)
			(layers "F.Cu" "F.Mask" "F.Paste")
			(net "GND")
		)
		(pad "D29" smd circle
			(at -13.212572 -23.617174)
			(size 0.4318 0.4318)
			(layers "F.Cu" "F.Mask" "F.Paste")
			(net "GND")
		)
		(pad "D31" smd circle
			(at -11.495532 -23.617174)
			(size 0.4318 0.4318)
			(layers "F.Cu" "F.Mask" "F.Paste")
			(net "GND")
		)
		(pad "D33" smd circle
			(at -9.778492 -23.617174)
			(size 0.4318 0.4318)
			(layers "F.Cu" "F.Mask" "F.Paste")
			(net "GND")
		)
		(pad "D35" smd circle
			(at -8.061452 -23.617174)
			(size 0.4318 0.4318)
			(layers "F.Cu" "F.Mask" "F.Paste")
			(net "GND")
		)
		(pad "D37" smd circle
			(at -6.344412 -23.617174)
			(size 0.4318 0.4318)
			(layers "F.Cu" "F.Mask" "F.Paste")
			(net "GND")
		)
		(pad "D39" smd circle
			(at -4.627626 -23.617174)
			(size 0.4318 0.4318)
			(layers "F.Cu" "F.Mask" "F.Paste")
			(net "GND")
		)
		(pad "D41" smd circle
			(at -2.910586 -23.617174)
			(size 0.4318 0.4318)
			(layers "F.Cu" "F.Mask" "F.Paste")
			(net "GND")
		)
		(pad "D43" smd circle
			(at -1.193546 -23.617174)
			(size 0.4318 0.4318)
			(layers "F.Cu" "F.Mask" "F.Paste")
			(net "GND")
		)
		(pad "D45" smd custom
			(at 2.052066 -25.417526 45)
			(size 0.10795 0.10795)
			(layers "F.Cu" "F.Mask" "F.Paste")
			(net "PVDDQ_ABC")
			(options
				(clearance outline)
				(anchor circle)
			)
			(primitives
				(gr_poly
					(pts
						(arc
							(start 0.2159 -0.0381)
							(mid 0 -0.254)
							(end -0.2159 -0.0381)
						)
						(arc
							(start -0.2159 0.0381)
							(mid 0 0.254)
							(end 0.2159 0.0381)
						)
					)
					(width 0)
					(fill yes)
				)
			)
		)
		(pad "D47" smd circle
			(at 3.769106 -25.417526)
			(size 0.4318 0.4318)
			(layers "F.Cu" "F.Mask" "F.Paste")
			(net "M_A_CS_N<2>")
		)
		(pad "D49" smd circle
			(at 5.485892 -25.417526)
			(size 0.4318 0.4318)
			(layers "F.Cu" "F.Mask" "F.Paste")
			(net "M_A_CS_N<5>")
		)
		(pad "D51" smd circle
			(at 7.202932 -25.417526)
			(size 0.4318 0.4318)
			(layers "F.Cu" "F.Mask" "F.Paste")
			(net "M_A_MA<16>")
		)
		(pad "D53" smd circle
			(at 8.919972 -25.417526)
			(size 0.4318 0.4318)
			(layers "F.Cu" "F.Mask" "F.Paste")
			(net "M_A_PAR")
		)
		(pad "D55" smd circle
			(at 10.637012 -25.417526)
			(size 0.4318 0.4318)
			(layers "F.Cu" "F.Mask" "F.Paste")
			(net "M_A_CLK_DP<0>")
		)
		(pad "D57" smd circle
			(at 12.354052 -25.417526)
			(size 0.4318 0.4318)
			(layers "F.Cu" "F.Mask" "F.Paste")
			(net "M_A_MA<2>")
		)
		(pad "D59" smd circle
			(at 14.071092 -25.417526)
			(size 0.4318 0.4318)
			(layers "F.Cu" "F.Mask" "F.Paste")
			(net "M_A_MA<6>")
		)
		(pad "D61" smd circle
			(at 15.787878 -25.417526)
			(size 0.4318 0.4318)
			(layers "F.Cu" "F.Mask" "F.Paste")
			(net "M_A_BG<0>")
		)
		(pad "D63" smd circle
			(at 17.504918 -25.417526)
			(size 0.4318 0.4318)
			(layers "F.Cu" "F.Mask" "F.Paste")
			(net "M_A_CKE<3>")
		)
		(pad "D65" smd custom
			(at 19.221958 -25.417526)
			(size 0.10795 0.10795)
			(layers "F.Cu" "F.Mask" "F.Paste")
			(net "TP_CPU0_RSVD_285")
			(options
				(clearance outline)
				(anchor circle)
			)
			(primitives
				(gr_poly
					(pts
						(arc
							(start 0.2159 -0.0381)
							(mid 0 -0.254)
							(end -0.2159 -0.0381)
						)
						(arc
							(start -0.2159 0.0381)
							(mid 0 0.254)
							(end 0.2159 0.0381)
						)
					)
					(width 0)
					(fill yes)
				)
			)
		)
		(pad "D71" smd custom
			(at 24.373078 -25.417526)
			(size 0.10795 0.10795)
			(layers "F.Cu" "F.Mask" "F.Paste")
			(net "M_B_DQ<26>")
			(options
				(clearance outline)
				(anchor circle)
			)
			(primitives
				(gr_poly
					(pts
						(arc
							(start 0.2159 -0.0381)
							(mid 0 -0.254)
							(end -0.2159 -0.0381)
						)
						(arc
							(start -0.2159 0.0381)
							(mid 0 0.254)
							(end 0.2159 0.0381)
						)
					)
					(width 0)
					(fill yes)
				)
			)
		)
		(pad "D73" smd circle
			(at 26.090118 -25.417526)
			(size 0.4318 0.4318)
			(layers "F.Cu" "F.Mask" "F.Paste")
			(net "M_B_DQS_DP<12>")
		)
		(pad "D75" smd circle
			(at 27.806904 -25.417526)
			(size 0.4318 0.4318)
			(layers "F.Cu" "F.Mask" "F.Paste")
			(net "M_B_DQ<24>")
		)
		(pad "D77" smd circle
			(at 29.523944 -25.417526)
			(size 0.4318 0.4318)
			(layers "F.Cu" "F.Mask" "F.Paste")
			(net "GND")
		)
		(pad "D79" smd circle
			(at 31.240984 -25.417526)
			(size 0.4318 0.4318)
			(layers "F.Cu" "F.Mask" "F.Paste")
			(net "M_B_DQS_DN<11>")
		)
		(pad "D81" smd custom
			(at 32.958024 -25.417526 315)
			(size 0.10795 0.10795)
			(layers "F.Cu" "F.Mask" "F.Paste")
			(net "GND")
			(options
				(clearance outline)
				(anchor circle)
			)
			(primitives
				(gr_poly
					(pts
						(arc
							(start 0.2159 -0.0381)
							(mid 0 -0.254)
							(end -0.2159 -0.0381)
						)
						(arc
							(start -0.2159 0.0381)
							(mid 0 0.254)
							(end 0.2159 0.0381)
						)
					)
					(width 0)
					(fill yes)
				)
			)
		)
		(pad "D83" smd custom
			(at 34.675064 -25.417526 270)
			(size 0.10795 0.10795)
			(layers "F.Cu" "F.Mask" "F.Paste")
			(net "TP_CPU0_RSVD_284")
			(options
				(clearance outline)
				(anchor circle)
			)
			(primitives
				(gr_poly
					(pts
						(arc
							(start 0.2159 -0.0381)
							(mid 0 -0.254)
							(end -0.2159 -0.0381)
						)
						(arc
							(start -0.2159 0.0381)
							(mid 0 0.254)
							(end 0.2159 0.0381)
						)
					)
					(width 0)
					(fill yes)
				)
			)
		)
		(pad "DA2" smd circle
			(at -36.392104 14.520926)
			(size 0.4318 0.4318)
			(layers "F.Cu" "F.Mask" "F.Paste")
			(net "P3E_CPU0_PE1_SS_TXN<0>")
		)
		(pad "DA4" smd circle
			(at -34.675064 14.520926)
			(size 0.4318 0.4318)
			(layers "F.Cu" "F.Mask" "F.Paste")
			(net "P3E_CPU0_PE3_OCP_TXP<14>")
		)
		(pad "DA6" smd circle
			(at -32.958024 14.520926)
			(size 0.4318 0.4318)
			(layers "F.Cu" "F.Mask" "F.Paste")
			(net "GND")
		)
		(pad "DA8" smd circle
			(at -31.240984 14.520926)
			(size 0.4318 0.4318)
			(layers "F.Cu" "F.Mask" "F.Paste")
			(net "P3E_CPU0_PE1_SS_RXN<1>")
		)
		(pad "DA10" smd circle
			(at -29.523944 14.520926)
			(size 0.4318 0.4318)
			(layers "F.Cu" "F.Mask" "F.Paste")
			(net "P3E_CPU0_PE1_SS_RXP<3>")
		)
		(pad "DA12" smd circle
			(at -27.806904 14.520926)
			(size 0.4318 0.4318)
			(layers "F.Cu" "F.Mask" "F.Paste")
			(net "P3E_CPU0_PE3_OCP_RXP<13>")
		)
		(pad "DA14" smd circle
			(at -26.090118 14.520926)
			(size 0.4318 0.4318)
			(layers "F.Cu" "F.Mask" "F.Paste")
			(net "PVCCIO_CPU0")
		)
		(pad "DA16" smd circle
			(at -24.373078 14.520926)
			(size 0.4318 0.4318)
			(layers "F.Cu" "F.Mask" "F.Paste")
			(net "TP_CPU0_UPI2_RSVD_DC16")
		)
		(pad "DA18" smd circle
			(at -22.656038 14.520926)
			(size 0.4318 0.4318)
			(layers "F.Cu" "F.Mask" "F.Paste")
			(net "GND")
		)
		(pad "DA20" smd circle
			(at -20.938998 14.520926)
			(size 0.4318 0.4318)
			(layers "F.Cu" "F.Mask" "F.Paste")
			(net "GND")
		)
		(pad "DA22" smd circle
			(at -19.221958 14.520926)
			(size 0.4318 0.4318)
			(layers "F.Cu" "F.Mask" "F.Paste")
			(net "GND")
		)
		(pad "DA24" smd circle
			(at -17.504918 14.520926)
			(size 0.4318 0.4318)
			(layers "F.Cu" "F.Mask" "F.Paste")
			(net "PVCCMCP_CPU0")
		)
		(pad "DA26" smd circle
			(at -15.787878 14.520926)
			(size 0.4318 0.4318)
			(layers "F.Cu" "F.Mask" "F.Paste")
			(net "GND")
		)
		(pad "DA28" smd circle
			(at -14.071092 14.520926)
			(size 0.4318 0.4318)
			(layers "F.Cu" "F.Mask" "F.Paste")
			(net "GND")
		)
		(pad "DA30" smd circle
			(at -12.354052 14.520926)
			(size 0.4318 0.4318)
			(layers "F.Cu" "F.Mask" "F.Paste")
			(net "GND")
		)
		(pad "DA32" smd circle
			(at -10.637012 14.520926)
			(size 0.4318 0.4318)
			(layers "F.Cu" "F.Mask" "F.Paste")
			(net "GND")
		)
		(pad "DA34" smd circle
			(at -8.919972 14.520926)
			(size 0.4318 0.4318)
			(layers "F.Cu" "F.Mask" "F.Paste")
			(net "GND")
		)
		(pad "DA36" smd circle
			(at -7.202932 14.520926)
			(size 0.4318 0.4318)
			(layers "F.Cu" "F.Mask" "F.Paste")
			(net "GND")
		)
		(pad "DA38" smd circle
			(at -5.485892 14.520926)
			(size 0.4318 0.4318)
			(layers "F.Cu" "F.Mask" "F.Paste")
			(net "GND")
		)
		(pad "DA40" smd circle
			(at -3.769106 14.520926)
			(size 0.4318 0.4318)
			(layers "F.Cu" "F.Mask" "F.Paste")
			(net "TP_CPU0_RSVD_51")
		)
		(pad "DA42" smd circle
			(at -2.052066 14.520926)
			(size 0.4318 0.4318)
			(layers "F.Cu" "F.Mask" "F.Paste")
			(net "M_F_DQ<36>")
		)
		(pad "DA44" smd circle
			(at 1.193546 12.720828)
			(size 0.508 0.508)
			(layers "F.Cu" "F.Mask" "F.Paste")
			(net "GND")
		)
		(pad "DA46" smd circle
			(at 2.910586 12.720828)
			(size 0.4318 0.4318)
			(layers "F.Cu" "F.Mask" "F.Paste")
			(net "GND")
		)
		(pad "DA48" smd circle
			(at 4.627626 12.720828)
			(size 0.4318 0.4318)
			(layers "F.Cu" "F.Mask" "F.Paste")
			(net "GND")
		)
	)
)
